#ISCELL
  logical_power design_note *
  *
#ISCELL
  pure_quanta quanta_title_block_c *
  *
#ISCELL
  standard offpage *
  page311_i1
#ISCELL
  standard offpage *
  page311_i10
#ISCELL
  standard offpage *
  page311_i14
#ISCELL
  standard offpage *
  page311_i15
#ISCELL
  standard offpage *
  page311_i16
#ISCELL
  standard offpage *
  page311_i17
#ISCELL
  standard offpage *
  page311_i18
#ISCELL
  standard offpage *
  page311_i19
#ISCELL
  standard offpage *
  page311_i2
#ISCELL
  standard offpage *
  page311_i20
#ISCELL
  standard offpage *
  page311_i21
#ISCELL
  standard offpage *
  page311_i22
#ISCELL
  standard offpage *
  page311_i23
#ISCELL
  standard offpage *
  page311_i24
#ISCELL
  standard offpage *
  page311_i25
#ISCELL
  standard offpage *
  page311_i26
#ISCELL
  standard offpage *
  page311_i27
#ISCELL
  logical_power universal_power *
  page311_i28
#CELL
  pure_quanta q_res *
  page311_i29
#ISCELL
  logical_power universal_power *
  page311_i3
#ISCELL
  standard offpage *
  page311_i30
#ISCELL
  standard offpage *
  page311_i31
#ISCELL
  standard offpage *
  page311_i32
#CELL
  pure_quanta lcmxo3lf9400c5bg484c *
  page311_i33
#ISCELL
  standard offpage *
  page311_i34
#ISCELL
  standard offpage *
  page311_i35
#ISCELL
  standard offpage *
  page311_i36
#ISCELL
  standard offpage *
  page311_i37
#ISCELL
  standard offpage *
  page311_i38
#ISCELL
  standard offpage *
  page311_i39
#CELL
  pure_quanta q_res *
  page311_i4
#ISCELL
  standard offpage *
  page311_i40
#ISCELL
  standard offpage *
  page311_i41
#ISCELL
  standard offpage *
  page311_i42
#ISCELL
  standard offpage *
  page311_i43
#ISCELL
  standard offpage *
  page311_i44
#ISCELL
  standard offpage *
  page311_i45
#ISCELL
  standard offpage *
  page311_i46
#ISCELL
  standard offpage *
  page311_i47
#ISCELL
  standard offpage *
  page311_i48
#ISCELL
  standard offpage *
  page311_i49
#ISCELL
  standard offpage *
  page311_i5
#ISCELL
  standard offpage *
  page311_i50
#ISCELL
  standard offpage *
  page311_i51
#ISCELL
  standard offpage *
  page311_i52
#ISCELL
  standard offpage *
  page311_i55
#ISCELL
  standard offpage *
  page311_i56
#ISCELL
  standard offpage *
  page311_i57
#ISCELL
  standard offpage *
  page311_i58
#ISCELL
  standard offpage *
  page311_i59
#ISCELL
  standard offpage *
  page311_i60
#ISCELL
  standard offpage *
  page311_i62
#ISCELL
  standard offpage *
  page311_i68
#ISCELL
  standard offpage *
  page311_i69
#ISCELL
  standard offpage *
  page311_i7
#CELL
  pure_quanta lcmxo3lf9400c5bg484c *
  page311_i70
#ISCELL
  standard offpage *
  page311_i71
#ISCELL
  standard offpage *
  page311_i72
#ISCELL
  standard offpage *
  page311_i73
#ISCELL
  standard offpage *
  page311_i74
#ISCELL
  standard offpage *
  page311_i75
#ISCELL
  standard offpage *
  page311_i76
#ISCELL
  standard offpage *
  page311_i77
#ISCELL
  standard offpage *
  page311_i78
#CELL
  pure_quanta q_res *
  page311_i79
#ISCELL
  standard offpage *
  page311_i8
#ISCELL
  standard offpage *
  page311_i80
#ISCELL
  standard offpage *
  page311_i81
#ISCELL
  standard offpage *
  page311_i82
#ISCELL
  standard offpage *
  page311_i83
#ISCELL
  standard offpage *
  page311_i84
#ISCELL
  standard offpage *
  page311_i85
#CELL
  pure_quanta q_res *
  page311_i86
#ISCELL
  standard offpage *
  page311_i87
#ISCELL
  standard offpage *
  page311_i88
#ISCELL
  standard offpage *
  page311_i89
#ISCELL
  standard offpage *
  page311_i9
#CELL
  pure_quanta q_res *
  page311_i90
#ISCELL
  standard offpage *
  page311_i91
#ISCELL
  standard offpage *
  page311_i92
#ISCELL
  standard offpage *
  page311_i93
#ISCELL
  standard offpage *
  page311_i94
#CELL
  pure_quanta q_res *
  page311_i95
#ISCELL
  standard offpage *
  page311_i96
#ISCELL
  standard offpage *
  page311_i97
#ISCELL
  standard offpage *
  page311_i98
